(kicad_pcb
	(version 20241229)
	(generator "pcbnew")
	(generator_version "9.0")
	(general
		(thickness 1.711)
		(legacy_teardrops no)
	)
	(paper "A4")
	(title_block
		(title "Antmicro Baseboard for Jetson AGX Thor")
		(date "2026-02-18")
		(rev "1.1.0")
		(company "Antmicro Ltd")
		(comment 1 "www.antmicro.com")
		(comment 9 "footprints 871-874 of 1170")
	)
	(layers
		(0 "F.Cu" signal)
		(4 "In1.Cu" signal)
		(6 "In2.Cu" signal)
		(8 "In3.Cu" signal)
		(10 "In4.Cu" jumper)
		(12 "In5.Cu" signal)
		(14 "In6.Cu" signal)
		(16 "In7.Cu" signal)
		(18 "In8.Cu" signal)
		(2 "B.Cu" signal)
		(9 "F.Adhes" user "F.Adhesive")
		(11 "B.Adhes" user "B.Adhesive")
		(13 "F.Paste" user)
		(15 "B.Paste" user)
		(5 "F.SilkS" user "F.Silkscreen")
		(7 "B.SilkS" user "B.Silkscreen")
		(1 "F.Mask" user)
		(3 "B.Mask" user)
		(17 "Dwgs.User" user "User.Drawings")
		(19 "Cmts.User" user "User.Comments")
		(21 "Eco1.User" user "User.Eco1")
		(23 "Eco2.User" user "User.Eco2")
		(25 "Edge.Cuts" user)
		(27 "Margin" user)
		(31 "F.CrtYd" user "F.Courtyard")
		(29 "B.CrtYd" user "B.Courtyard")
		(35 "F.Fab" user)
		(33 "B.Fab" user)
	)
	(footprint "antmicro-footprints:Spacer_Drill3.7mm_H8mm_9774080151R"
		(locked yes)
		(layer "B.Cu")
		(at 108.930532 112.71 180)
		(descr "Spacer M=3 h=8mm fi=5.1mm")
		(property "Reference" "H13"
			(at 0 3.2 0)
			(layer "B.SilkS")
			(effects
				(font
					(size 0.7 0.7)
					(thickness 0.15)
				)
				(justify left bottom mirror)
			)
		)
		(property "Value" "Spacer_Drill3.7mm_H8mm_9774080151R"
			(at 0 -4 0)
			(layer "B.Fab")
			(effects
				(font
					(size 0.7 0.7)
					(thickness 0.15)
				)
				(justify left bottom mirror)
			)
		)
		(property "Datasheet" "https://www.we-online.com/components/products/datasheet/9774080151R.pdf"
			(at 0 0 0)
			(layer "B.Fab")
			(hide yes)
			(effects
				(font
					(size 1.27 1.27)
					(thickness 0.15)
				)
				(justify mirror)
			)
		)
		(property "Description" "Spacer, SMT, Non Stop, Steel, Swage Round, 5.1 mm x 8 mm, M2.5 Thread, WA-SMSI Series"
			(at 0 0 0)
			(layer "B.Fab")
			(hide yes)
			(effects
				(font
					(size 1.27 1.27)
					(thickness 0.15)
				)
				(justify mirror)
			)
		)
		(property "Manufacturer" "Würth Elektronik"
			(at 0 0 180)
			(unlocked yes)
			(layer "B.Fab")
			(hide yes)
			(effects
				(font
					(size 1 1)
					(thickness 0.15)
				)
				(justify mirror)
			)
		)
		(property "MPN" "9774080151R"
			(at 0 0 180)
			(unlocked yes)
			(layer "B.Fab")
			(hide yes)
			(effects
				(font
					(size 1 1)
					(thickness 0.15)
				)
				(justify mirror)
			)
		)
		(property "Author" "Antmicro"
			(at 0 0 180)
			(unlocked yes)
			(layer "B.Fab")
			(hide yes)
			(effects
				(font
					(size 1 1)
					(thickness 0.15)
				)
				(justify mirror)
			)
		)
		(property "License" "Apache-2.0"
			(at 0 0 180)
			(unlocked yes)
			(layer "B.Fab")
			(hide yes)
			(effects
				(font
					(size 1 1)
					(thickness 0.15)
				)
				(justify mirror)
			)
		)
		(sheetname "/")
		(sheetfile "jetson-agx-thor-baseboard.kicad_sch")
		(solder_paste_margin_ratio -1)
		(attr smd)
		(fp_circle
			(center 0 0)
			(end 3.05 0)
			(stroke
				(width 0.05)
				(type solid)
			)
			(fill no)
			(layer "B.CrtYd")
		)
		(fp_circle
			(center 0 0)
			(end 2.6 0)
			(stroke
				(width 0.15)
				(type solid)
			)
			(fill no)
			(layer "B.Fab")
		)
		(fp_text user "License: Apache-2.0"
			(at -9.6 -8.9 0)
			(layer "B.Fab")
			(effects
				(font
					(size 0.7 0.7)
					(thickness 0.15)
				)
				(justify left bottom mirror)
			)
		)
		(fp_text user "Author: Antmicro"
			(at -9.6 -7.7 0)
			(layer "B.Fab")
			(effects
				(font
					(size 0.7 0.7)
					(thickness 0.15)
				)
				(justify left bottom mirror)
			)
		)
		(fp_text user "${REFERENCE}"
			(at -9.6 -6.5 0)
			(layer "B.Fab")
			(effects
				(font
					(size 0.7 0.7)
					(thickness 0.15)
				)
				(justify left bottom mirror)
			)
		)
		(pad "" smd custom
			(at -1.7 -1.7 90)
			(size 0.62 0.62)
			(layers "B.Paste")
			(thermal_bridge_angle 90)
			(options
				(clearance outline)
				(anchor circle)
			)
			(primitives
				(gr_arc
					(start 1.266786 0.24747)
					(mid 0.285453 -0.29439)
					(end -0.250195 -1.279127)
					(width 0.2)
				)
				(gr_arc
					(start 1.259603 0.339191)
					(mid 0.218448 -0.232561)
					(end -0.34334 -1.279127)
					(width 0.2)
				)
				(gr_arc
					(start 1.255279 0.431435)
					(mid 0.152481 -0.169693)
					(end -0.436309 -1.279127)
					(width 0.2)
				)
				(gr_arc
					(start 1.253811 0.524161)
					(mid 0.087542 -0.105784)
					(end -0.529126 -1.279127)
					(width 0.2)
				)
				(gr_arc
					(start 1.275473 0.621136)
					(mid 0.0309 -0.033527)
					(end -0.621807 -1.279127)
					(width 0.2)
				)
				(gr_arc
					(start 1.263664 0.711602)
					(mid -0.037759 0.026651)
					(end -0.71437 -1.279127)
					(width 0.2)
				)
				(gr_arc
					(start 1.253435 0.802342)
					(mid -0.105837 0.087395)
					(end -0.806826 -1.279127)
					(width 0.2)
				)
				(gr_arc
					(start 1.267475 0.897258)
					(mid -0.165236 0.156885)
					(end -0.899187 -1.279127)
					(width 0.2)
				)
				(gr_arc
					(start 1.270645 0.990112)
					(mid -0.228522 0.222449)
					(end -0.991463 -1.279127)
					(width 0.2)
				)
				(gr_arc
					(start 1.266278 1.081674)
					(mid -0.294507 0.285313)
					(end -1.083663 -1.279127)
					(width 0.2)
				)
				(gr_line
					(start 1.279127 0.250195)
					(end 1.279127 1.083663)
					(width 0.2)
				)
				(gr_line
					(start -0.250195 -1.279127)
					(end -1.083663 -1.279127)
					(width 0.2)
				)
			)
		)
		(pad "" smd custom
			(at -1.7 1.7 180)
			(size 0.62 0.62)
			(layers "B.Paste")
			(thermal_bridge_angle 90)
			(options
				(clearance outline)
				(anchor circle)
			)
			(primitives
				(gr_arc
					(start 1.266786 0.24747)
					(mid 0.285453 -0.29439)
					(end -0.250195 -1.279127)
					(width 0.2)
				)
				(gr_arc
					(start 1.259603 0.339191)
					(mid 0.218448 -0.232561)
					(end -0.34334 -1.279127)
					(width 0.2)
				)
				(gr_arc
					(start 1.255279 0.431435)
					(mid 0.152481 -0.169693)
					(end -0.436309 -1.279127)
					(width 0.2)
				)
				(gr_arc
					(start 1.253811 0.524161)
					(mid 0.087542 -0.105784)
					(end -0.529126 -1.279127)
					(width 0.2)
				)
				(gr_arc
					(start 1.275473 0.621136)
					(mid 0.0309 -0.033527)
					(end -0.621807 -1.279127)
					(width 0.2)
				)
				(gr_arc
					(start 1.263664 0.711602)
					(mid -0.037759 0.026651)
					(end -0.71437 -1.279127)
					(width 0.2)
				)
				(gr_arc
					(start 1.253435 0.802342)
					(mid -0.105837 0.087395)
					(end -0.806826 -1.279127)
					(width 0.2)
				)
				(gr_arc
					(start 1.267475 0.897258)
					(mid -0.165236 0.156885)
					(end -0.899187 -1.279127)
					(width 0.2)
				)
				(gr_arc
					(start 1.270645 0.990112)
					(mid -0.228522 0.222449)
					(end -0.991463 -1.279127)
					(width 0.2)
				)
				(gr_arc
					(start 1.266278 1.081674)
					(mid -0.294507 0.285313)
					(end -1.083663 -1.279127)
					(width 0.2)
				)
				(gr_line
					(start 1.279127 0.250195)
					(end 1.279127 1.083663)
					(width 0.2)
				)
				(gr_line
					(start -0.250195 -1.279127)
					(end -1.083663 -1.279127)
					(width 0.2)
				)
			)
		)
		(pad "" smd custom
			(at 1.7 -1.7)
			(size 0.62 0.62)
			(layers "B.Paste")
			(thermal_bridge_angle 90)
			(options
				(clearance outline)
				(anchor circle)
			)
			(primitives
				(gr_arc
					(start 1.266786 0.24747)
					(mid 0.285453 -0.29439)
					(end -0.250195 -1.279127)
					(width 0.2)
				)
				(gr_arc
					(start 1.259603 0.339191)
					(mid 0.218448 -0.232561)
					(end -0.34334 -1.279127)
					(width 0.2)
				)
				(gr_arc
					(start 1.255279 0.431435)
					(mid 0.152481 -0.169693)
					(end -0.436309 -1.279127)
					(width 0.2)
				)
				(gr_arc
					(start 1.253811 0.524161)
					(mid 0.087542 -0.105784)
					(end -0.529126 -1.279127)
					(width 0.2)
				)
				(gr_arc
					(start 1.275473 0.621136)
					(mid 0.0309 -0.033527)
					(end -0.621807 -1.279127)
					(width 0.2)
				)
				(gr_arc
					(start 1.263664 0.711602)
					(mid -0.037759 0.026651)
					(end -0.71437 -1.279127)
					(width 0.2)
				)
				(gr_arc
					(start 1.253435 0.802342)
					(mid -0.105837 0.087395)
					(end -0.806826 -1.279127)
					(width 0.2)
				)
				(gr_arc
					(start 1.267475 0.897258)
					(mid -0.165236 0.156885)
					(end -0.899187 -1.279127)
					(width 0.2)
				)
				(gr_arc
					(start 1.270645 0.990112)
					(mid -0.228522 0.222449)
					(end -0.991463 -1.279127)
					(width 0.2)
				)
				(gr_arc
					(start 1.266278 1.081674)
					(mid -0.294507 0.285313)
					(end -1.083663 -1.279127)
					(width 0.2)
				)
				(gr_line
					(start 1.279127 0.250195)
					(end 1.279127 1.083663)
					(width 0.2)
				)
				(gr_line
					(start -0.250195 -1.279127)
					(end -1.083663 -1.279127)
					(width 0.2)
				)
			)
		)
		(pad "" smd custom
			(at 1.7 1.7 270)
			(size 0.62 0.62)
			(layers "B.Paste")
			(thermal_bridge_angle 90)
			(options
				(clearance outline)
				(anchor circle)
			)
			(primitives
				(gr_arc
					(start 1.266786 0.24747)
					(mid 0.285453 -0.29439)
					(end -0.250195 -1.279127)
					(width 0.2)
				)
				(gr_arc
					(start 1.259603 0.339191)
					(mid 0.218448 -0.232561)
					(end -0.34334 -1.279127)
					(width 0.2)
				)
				(gr_arc
					(start 1.255279 0.431435)
					(mid 0.152481 -0.169693)
					(end -0.436309 -1.279127)
					(width 0.2)
				)
				(gr_arc
					(start 1.253811 0.524161)
					(mid 0.087542 -0.105784)
					(end -0.529126 -1.279127)
					(width 0.2)
				)
				(gr_arc
					(start 1.275473 0.621136)
					(mid 0.0309 -0.033527)
					(end -0.621807 -1.279127)
					(width 0.2)
				)
				(gr_arc
					(start 1.263664 0.711602)
					(mid -0.037759 0.026651)
					(end -0.71437 -1.279127)
					(width 0.2)
				)
				(gr_arc
					(start 1.253435 0.802342)
					(mid -0.105837 0.087395)
					(end -0.806826 -1.279127)
					(width 0.2)
				)
				(gr_arc
					(start 1.267475 0.897258)
					(mid -0.165236 0.156885)
					(end -0.899187 -1.279127)
					(width 0.2)
				)
				(gr_arc
					(start 1.270645 0.990112)
					(mid -0.228522 0.222449)
					(end -0.991463 -1.279127)
					(width 0.2)
				)
				(gr_arc
					(start 1.266278 1.081674)
					(mid -0.294507 0.285313)
					(end -1.083663 -1.279127)
					(width 0.2)
				)
				(gr_line
					(start 1.279127 0.250195)
					(end 1.279127 1.083663)
					(width 0.2)
				)
				(gr_line
					(start -0.250195 -1.279127)
					(end -1.083663 -1.279127)
					(width 0.2)
				)
			)
		)
		(pad "1" thru_hole circle
			(at 0 0 180)
			(size 6 6)
			(drill 3.7)
			(layers "*.Cu" "*.Mask")
			(remove_unused_layers no)
			(net 1 "GND")
			(pintype "passive")
		)
	)
	(footprint "antmicro-footprints:TP_SMD_0.75mm"
		(layer "B.Cu")
		(at 129.2 69.2 -45)
		(property "Reference" "TP105"
			(at -2.446589 -3.082986 270)
			(layer "B.SilkS")
			(effects
				(font
					(size 0.7 0.7)
					(thickness 0.15)
				)
				(justify left bottom mirror)
			)
		)
		(property "Value" "TP_0.75mm_SMD"
			(at 0 -1.2 135)
			(layer "B.Fab")
			(effects
				(font
					(size 0.7 0.7)
					(thickness 0.15)
				)
				(justify left bottom mirror)
			)
		)
		(property "Description" "SMT test point"
			(at 0 0 135)
			(layer "B.Fab")
			(hide yes)
			(effects
				(font
					(size 1.27 1.27)
					(thickness 0.15)
				)
				(justify mirror)
			)
		)
		(property "MPN" ""
			(at 0 0 135)
			(unlocked yes)
			(layer "B.Fab")
			(hide yes)
			(effects
				(font
					(size 1 1)
					(thickness 0.15)
				)
				(justify mirror)
			)
		)
		(property "Manufacturer" ""
			(at 0 0 135)
			(unlocked yes)
			(layer "B.Fab")
			(hide yes)
			(effects
				(font
					(size 1 1)
					(thickness 0.15)
				)
				(justify mirror)
			)
		)
		(property "Author" "Antmicro"
			(at 0 0 135)
			(unlocked yes)
			(layer "B.Fab")
			(hide yes)
			(effects
				(font
					(size 1 1)
					(thickness 0.15)
				)
				(justify mirror)
			)
		)
		(property "License" "Apache-2.0"
			(at 0 0 135)
			(unlocked yes)
			(layer "B.Fab")
			(hide yes)
			(effects
				(font
					(size 1 1)
					(thickness 0.15)
				)
				(justify mirror)
			)
		)
		(sheetname "/SoM_IO/")
		(sheetfile "som_io.kicad_sch")
		(attr exclude_from_pos_files exclude_from_bom)
		(fp_circle
			(center 0 0)
			(end 0.475 0)
			(stroke
				(width 0.05)
				(type default)
			)
			(fill no)
			(layer "B.CrtYd")
		)
		(fp_text user "${REFERENCE}"
			(at -0.4 -2.7 135)
			(layer "B.Fab")
			(effects
				(font
					(size 0.7 0.7)
					(thickness 0.15)
				)
				(justify left bottom mirror)
			)
		)
		(fp_text user "Author: Antmicro"
			(at -0.4 -3.901 135)
			(layer "B.Fab")
			(effects
				(font
					(size 0.7 0.7)
					(thickness 0.15)
				)
				(justify left bottom mirror)
			)
		)
		(fp_text user "License: Apache-2.0"
			(at -0.4 -5.101 135)
			(layer "B.Fab")
			(effects
				(font
					(size 0.7 0.7)
					(thickness 0.15)
				)
				(justify left bottom mirror)
			)
		)
		(pad "1" smd circle
			(at 0 0 315)
			(size 0.75 0.75)
			(layers "B.Cu" "B.Mask")
			(net 126 "/SoM_IO/UART1.RTS")
			(pinfunction "1")
			(pintype "passive")
		)
	)
	(footprint "antmicro-footprints:TP_SMD_0.75mm"
		(layer "B.Cu")
		(at 90.1 81.6 90)
		(property "Reference" "TP53"
			(at -0.8 0.7 90)
			(layer "B.SilkS")
			(effects
				(font
					(size 0.7 0.7)
					(thickness 0.15)
				)
				(justify right top mirror)
			)
		)
		(property "Value" "TP_0.75mm_SMD"
			(at 0 -1.2 90)
			(layer "B.Fab")
			(effects
				(font
					(size 0.7 0.7)
					(thickness 0.15)
				)
				(justify right top mirror)
			)
		)
		(property "Description" "SMT test point"
			(at 0 0 90)
			(layer "B.Fab")
			(hide yes)
			(effects
				(font
					(size 1.27 1.27)
					(thickness 0.15)
				)
				(justify mirror)
			)
		)
		(property "MPN" ""
			(at 0 0 270)
			(unlocked yes)
			(layer "B.Fab")
			(hide yes)
			(effects
				(font
					(size 1 1)
					(thickness 0.15)
				)
				(justify mirror)
			)
		)
		(property "Manufacturer" ""
			(at 0 0 270)
			(unlocked yes)
			(layer "B.Fab")
			(hide yes)
			(effects
				(font
					(size 1 1)
					(thickness 0.15)
				)
				(justify mirror)
			)
		)
		(property "Author" "Antmicro"
			(at 0 0 270)
			(unlocked yes)
			(layer "B.Fab")
			(hide yes)
			(effects
				(font
					(size 1 1)
					(thickness 0.15)
				)
				(justify mirror)
			)
		)
		(property "License" "Apache-2.0"
			(at 0 0 270)
			(unlocked yes)
			(layer "B.Fab")
			(hide yes)
			(effects
				(font
					(size 1 1)
					(thickness 0.15)
				)
				(justify mirror)
			)
		)
		(sheetname "/SoM_Power/")
		(sheetfile "som_power.kicad_sch")
		(attr exclude_from_pos_files exclude_from_bom)
		(fp_circle
			(center 0 0)
			(end 0.475 0)
			(stroke
				(width 0.05)
				(type default)
			)
			(fill no)
			(layer "B.CrtYd")
		)
		(fp_text user "License: Apache-2.0"
			(at -0.4 -5.101 90)
			(layer "B.Fab")
			(effects
				(font
					(size 0.7 0.7)
					(thickness 0.15)
				)
				(justify right top mirror)
			)
		)
		(fp_text user "Author: Antmicro"
			(at -0.4 -3.901 90)
			(layer "B.Fab")
			(effects
				(font
					(size 0.7 0.7)
					(thickness 0.15)
				)
				(justify right top mirror)
			)
		)
		(fp_text user "${REFERENCE}"
			(at -0.4 -2.7 90)
			(layer "B.Fab")
			(effects
				(font
					(size 0.7 0.7)
					(thickness 0.15)
				)
				(justify right top mirror)
			)
		)
		(pad "1" smd circle
			(at 0 0 90)
			(size 0.75 0.75)
			(layers "B.Cu" "B.Mask")
			(net 796 "Net-(J1A-UFS0_RST_N)")
			(pinfunction "1")
			(pintype "passive")
		)
	)
	(footprint "antmicro-footprints:C_0402_1005Metric"
		(layer "B.Cu")
		(at 94 117.8 180)
		(descr "Capacitor SMD 0402")
		(tags "capacitor SMD 0402")
		(property "Reference" "C219"
			(at -3.8 -0.655 0)
			(layer "B.SilkS")
			(effects
				(font
					(size 0.7 0.7)
					(thickness 0.15)
				)
				(justify left bottom mirror)
			)
		)
		(property "Value" "C_220n_0402"
			(at -1.022927 -2.155213 0)
			(layer "B.Fab")
			(effects
				(font
					(size 0.7 0.7)
					(thickness 0.15)
				)
				(justify left bottom mirror)
			)
		)
		(property "Datasheet" "https://www.yageo.com/en/Chart/Download/pdf/CC0402KRX5R6BB224"
			(at 0 0 0)
			(layer "B.Fab")
			(hide yes)
			(effects
				(font
					(size 1.27 1.27)
					(thickness 0.15)
				)
				(justify mirror)
			)
		)
		(property "Description" "SMD Multilayer Ceramic Capacitor, 0.22 µF, 10 V, 0402 [1005 Metric], ± 10%, X5R, CC Series"
			(at 0 0 0)
			(layer "B.Fab")
			(hide yes)
			(effects
				(font
					(size 1.27 1.27)
					(thickness 0.15)
				)
				(justify mirror)
			)
		)
		(property "MPN" "CC0402KRX5R6BB224"
			(at 0 0 180)
			(unlocked yes)
			(layer "B.Fab")
			(hide yes)
			(effects
				(font
					(size 1 1)
					(thickness 0.15)
				)
				(justify mirror)
			)
		)
		(property "Val" "220n"
			(at 0 0 180)
			(unlocked yes)
			(layer "B.Fab")
			(hide yes)
			(effects
				(font
					(size 1 1)
					(thickness 0.15)
				)
				(justify mirror)
			)
		)
		(property "Voltage" "25V"
			(at 0 0 180)
			(unlocked yes)
			(layer "B.Fab")
			(hide yes)
			(effects
				(font
					(size 1 1)
					(thickness 0.15)
				)
				(justify mirror)
			)
		)
		(property "Dielectric" "X7R"
			(at 0 0 180)
			(unlocked yes)
			(layer "B.Fab")
			(hide yes)
			(effects
				(font
					(size 1 1)
					(thickness 0.15)
				)
				(justify mirror)
			)
		)
		(property "Manufacturer" "YAGEO"
			(at 0 0 180)
			(unlocked yes)
			(layer "B.Fab")
			(hide yes)
			(effects
				(font
					(size 1 1)
					(thickness 0.15)
				)
				(justify mirror)
			)
		)
		(property "License" "Apache-2.0"
			(at 0 0 180)
			(unlocked yes)
			(layer "B.Fab")
			(hide yes)
			(effects
				(font
					(size 1 1)
					(thickness 0.15)
				)
				(justify mirror)
			)
		)
		(property "Author" "Antmicro"
			(at 0 0 180)
			(unlocked yes)
			(layer "B.Fab")
			(hide yes)
			(effects
				(font
					(size 1 1)
					(thickness 0.15)
				)
				(justify mirror)
			)
		)
		(property "Public" "False"
			(at 0 0 180)
			(unlocked yes)
			(layer "B.Fab")
			(hide yes)
			(effects
				(font
					(size 1 1)
					(thickness 0.15)
				)
				(justify mirror)
			)
		)
		(sheetname "/Expansion connector/")
		(sheetfile "expansion_connector.kicad_sch")
		(attr smd)
		(fp_poly
			(pts
				(xy -0.925 0.47) (xy 0.925 0.47) (xy 0.925 -0.47) (xy -0.925 -0.47)
			)
			(stroke
				(width 0.05)
				(type default)
			)
			(fill no)
			(layer "B.CrtYd")
		)
		(fp_line
			(start 0.504 0.25)
			(end 0.504 -0.248)
			(stroke
				(width 0.15)
				(type solid)
			)
			(layer "B.Fab")
		)
		(fp_line
			(start 0.504 -0.248)
			(end -0.494 -0.248)
			(stroke
				(width 0.15)
				(type solid)
			)
			(layer "B.Fab")
		)
		(fp_line
			(start -0.494 0.25)
			(end 0.504 0.25)
			(stroke
				(width 0.15)
				(type solid)
			)
			(layer "B.Fab")
		)
		(fp_line
			(start -0.494 -0.248)
			(end -0.494 0.25)
			(stroke
				(width 0.15)
				(type solid)
			)
			(layer "B.Fab")
		)
		(fp_text user "Author: Antmicro"
			(at -0.939 -3.399 0)
			(layer "B.Fab")
			(effects
				(font
					(size 0.7 0.7)
					(thickness 0.15)
				)
				(justify left bottom mirror)
			)
		)
		(fp_text user "License: Apache-2.0"
			(at -0.939 -5.799 0)
			(layer "B.Fab")
			(effects
				(font
					(size 0.7 0.7)
					(thickness 0.15)
				)
				(justify left bottom mirror)
			)
		)
		(fp_text user "${REFERENCE}"
			(at -0.939 -4.599 0)
			(layer "B.Fab")
			(effects
				(font
					(size 0.7 0.7)
					(thickness 0.15)
				)
				(justify left bottom mirror)
			)
		)
		(pad "1" smd roundrect
			(at -0.48 0 180)
			(size 0.59 0.64)
			(layers "B.Cu" "B.Mask" "B.Paste")
			(roundrect_rratio 0.25)
			(net 517 "/Expansion connector/PCIe_{C3x2}.TX0-")
			(pintype "passive")
		)
		(pad "2" smd roundrect
			(at 0.48 0 180)
			(size 0.59 0.64)
			(layers "B.Cu" "B.Mask" "B.Paste")
			(roundrect_rratio 0.25)
			(net 518 "/Expansion connector/PET0_C3_N")
			(pintype "passive")
		)
	)
)
